FILE_TYPE = CONNECTIVITY;
{Allegro Design Entry HDL 17.4-2019 S026 (4007227) 1/17/2022}
"PAGE_NUMBER" = 14;
0"NC";
1"M_E_CPU0_SB_DQS_DN<9:0>";
2"M_E_CPU0_SB_DQ<31:0>";
3"M_E_CPU0_SB_CB<7:0>";
4"M_E_CPU0_SA_DQS_DN<9:0>";
5"M_E_CPU0_SA_DQS_DP<9:0>";
6"M_E_CPU0_SB_DQS_DP<9:0>";
7"M_E_CPU0_SA_DQ<31:0>";
8"M_E_CPU0_SA_CB<7:0>";
9"M_E_CPU0_SA_CA<6:0>";
10"M_E_CPU0_SB_CA<6:0>";
11"TP_M_E_CPU0_SA_TEST39E";
12"M_E_CPU0_CLK_DN<0>";
13"M_E_CPU0_CLK_DP<0>";
14"M_E_CPU0_SB_DQS_DP<9>";
15"M_E_CPU0_SB_PAR";
16"M_E_CPU0_SA_PAR";
17"M_E_CPU0_SA_DQS_DP<3>";
18"M_E_CPU0_SA_DQS_DN<7>";
19"M_E_CPU0_SB_CB<5>";
20"M_E_CPU0_SB_DQ<14>";
21"M_E_CPU0_SB_DQ<25>";
22"M_E_CPU0_SB_DQS_DN<1>";
23"M_E_CPU0_SA_DQ<19>";
24"M_E_CPU0_SA_DQS_DP<2>";
25"M_E_CPU0_SA_DQS_DN<6>";
26"M_E_CPU0_SB_CB<4>";
27"M_E_CPU0_SB_DQ<13>";
28"M_E_CPU0_SB_DQ<24>";
29"M_E_CPU0_SB_DQS_DN<0>";
30"M_E_CPU0_SA_DQ<18>";
31"M_E_CPU0_SA_DQ<29>";
32"M_E_CPU0_SA_DQS_DP<1>";
33"M_E_CPU0_SA_DQS_DN<5>";
34"M_E_CPU0_SB_CB<3>";
35"M_E_CPU0_SB_DQ<12>";
36"M_E_CPU0_SB_DQ<23>";
37"M_E_CPU0_SA_DQ<17>";
38"M_E_CPU0_SA_DQ<28>";
39"M_E_CPU0_SA_DQS_DP<0>";
40"M_E_CPU0_SA_DQS_DN<4>";
41"M_E_CPU0_SB_CB<2>";
42"M_E_CPU0_SB_DQ<9>";
43"M_E_CPU0_SB_DQ<11>";
44"M_E_CPU0_SB_DQ<22>";
45"M_E_CPU0_SA_RSP<0>";
46"M_E_CPU0_SA_CB<7>";
47"M_E_CPU0_SA_DQ<9>";
48"M_E_CPU0_SA_DQ<16>";
49"M_E_CPU0_SA_DQ<27>";
50"M_E_CPU0_SA_DQS_DN<3>";
51"M_E_CPU0_SB_CA<6>";
52"M_E_CPU0_SB_CB<1>";
53"M_E_CPU0_SB_DQ<8>";
54"M_E_CPU0_SB_DQ<10>";
55"M_E_CPU0_SB_DQ<21>";
56"M_E_CPU0_SA_CA<6>";
57"M_E_CPU0_SA_CB<6>";
58"M_E_CPU0_SA_DQ<8>";
59"M_E_CPU0_SA_DQ<15>";
60"M_E_CPU0_SA_DQ<26>";
61"M_E_CPU0_SA_DQS_DN<2>";
62"M_E_CPU0_SB_CA<5>";
63"M_E_CPU0_SB_CB<0>";
64"M_E_CPU0_SB_DQ<7>";
65"M_E_CPU0_SB_DQ<20>";
66"M_E_CPU0_SB_DQ<31>";
67"M_E_CPU0_SA_CA<5>";
68"M_E_CPU0_SA_CB<5>";
69"M_E_CPU0_SA_DQ<7>";
70"M_E_CPU0_SA_DQ<14>";
71"M_E_CPU0_SA_DQ<25>";
72"M_E_CPU0_SA_DQS_DN<1>";
73"M_E_CPU0_SB_CS_N<1>";
74"M_E_CPU0_SB_CA<4>";
75"M_E_CPU0_SB_DQ<6>";
76"M_E_CPU0_SB_DQ<30>";
77"M_E_CPU0_SB_DQS_DP<8>";
78"M_E_CPU0_SA_CA<4>";
79"M_E_CPU0_SA_CB<4>";
80"M_E_CPU0_SA_DQ<6>";
81"M_E_CPU0_SA_DQ<13>";
82"M_E_CPU0_SA_DQ<24>";
83"M_E_CPU0_SA_DQS_DN<0>";
84"M_E_CPU0_SB_CS_N<0>";
85"M_E_CPU0_SB_CA<3>";
86"M_E_CPU0_SB_DQ<5>";
87"M_E_CPU0_SB_DQS_DP<7>";
88"M_E_CPU0_SA_CA<3>";
89"M_E_CPU0_SA_CB<3>";
90"M_E_CPU0_SA_DQ<5>";
91"M_E_CPU0_SA_DQ<12>";
92"M_E_CPU0_SA_DQ<23>";
93"M_E_CPU0_SB_CA<2>";
94"M_E_CPU0_SB_DQ<4>";
95"M_E_CPU0_SB_DQS_DP<6>";
96"M_E_CPU0_SA_CA<2>";
97"M_E_CPU0_SA_CB<2>";
98"M_E_CPU0_SA_DQ<4>";
99"M_E_CPU0_SA_DQ<11>";
100"M_E_CPU0_SA_DQ<22>";
101"M_E_CPU0_SB_CA<1>";
102"M_E_CPU0_SB_DQ<3>";
103"M_E_CPU0_SB_DQS_DP<5>";
104"M_E_CPU0_SB_DQS_DN<9>";
105"M_E_CPU0_SA_CA<1>";
106"M_E_CPU0_SA_CB<1>";
107"M_E_CPU0_SA_DQ<3>";
108"M_E_CPU0_SA_DQ<10>";
109"M_E_CPU0_SA_DQ<21>";
110"M_E_CPU0_SB_CA<0>";
111"M_E_CPU0_SB_DQ<2>";
112"M_E_CPU0_SB_DQS_DP<4>";
113"M_E_CPU0_SB_DQS_DN<8>";
114"M_E_CPU0_SA_CA<0>";
115"M_E_CPU0_SA_CB<0>";
116"M_E_CPU0_SA_DQ<2>";
117"M_E_CPU0_SA_DQ<20>";
118"M_E_CPU0_SA_DQ<31>";
119"M_E_CPU0_SA_DQS_DP<9>";
120"M_E_CPU0_SB_DQ<1>";
121"M_E_CPU0_SB_DQS_DP<3>";
122"M_E_CPU0_SB_DQS_DN<7>";
123"M_E_CPU0_SA_CS_N<1>";
124"M_E_CPU0_SA_DQ<1>";
125"M_E_CPU0_SA_DQ<30>";
126"M_E_CPU0_SA_DQS_DP<8>";
127"M_E_CPU0_SB_DQ<0>";
128"M_E_CPU0_SB_DQ<19>";
129"M_E_CPU0_SB_DQS_DP<2>";
130"M_E_CPU0_SB_DQS_DN<6>";
131"M_E_CPU0_SA_CS_N<0>";
132"M_E_CPU0_SA_DQ<0>";
133"M_E_CPU0_SA_DQS_DP<7>";
134"M_E_CPU0_SB_DQ<18>";
135"M_E_CPU0_SB_DQ<29>";
136"M_E_CPU0_SB_DQS_DP<1>";
137"M_E_CPU0_SB_DQS_DN<5>";
138"M_E_CPU0_SA_DQS_DP<6>";
139"M_E_CPU0_SB_DQ<17>";
140"M_E_CPU0_SB_DQ<28>";
141"M_E_CPU0_SB_DQS_DP<0>";
142"M_E_CPU0_SB_DQS_DN<4>";
143"M_E_CPU0_SA_DQS_DP<5>";
144"M_E_CPU0_SA_DQS_DN<9>";
145"M_E_CPU0_SB_RSP<0>";
146"M_E_CPU0_SB_CB<7>";
147"M_E_CPU0_SB_DQ<16>";
148"M_E_CPU0_SB_DQ<27>";
149"M_E_CPU0_SB_DQS_DN<3>";
150"M_E_CPU0_SA_DQS_DP<4>";
151"M_E_CPU0_SA_DQS_DN<8>";
152"M_E_CPU0_SB_CB<6>";
153"M_E_CPU0_SB_DQ<15>";
154"M_E_CPU0_SB_DQ<26>";
155"M_E_CPU0_SB_DQS_DN<2>";
156"M_E_CPU0_RESET_N";
157"M_E_CPU0_ALERT_R_N";
158"M_E_CPU0_ALERT_N";
%"GENOA_SP5"
"5","(-4675,3675)","0","pure_quanta","I159";
;
LOCATION"U25"
$SEC"5"
CDS_SEC"5"
VALUE"SOCKET6096_13568-001"
MATERIAL"IO"
PART_TYPE"SMLF"
NEEDS_NO_SIZE"TRUE"
CDS_LMAN_SYM_OUTLINE"-650,2525,650,-2525"
CDS_LIB"pure_quanta"
PART_NUMBER"DGA^6000030";
"TEST39E"
$PN"BF69"11;
"ME1_CLK_L"
$PN"BG71"0;
"ME1_CLK_H"
$PN"BF70"0;
"ME0_CLK_L"
$PN"BD70"12;
"ME0_CLK_H"
$PN"BC71"13;
"MEB_DQS_H9"
$PN"BV70"14;
"MEB_PAR"
$PN"BL71"15;
"MEA_PAR"
$PN"BC69"16;
"MEA_DQS_H3"
$PN"AE71"17;
"MEA_DQS_L7"
$PN"Y69"18;
"MEB_CHECK5"
$PN"BU69"19;
"MEB_DATA14"
$PN"CN71"20;
"MEB_DATA25"
$PN"DA69"21;
"MEB_DQS_L1"
$PN"CL71"22;
"MEA_DATA19"
$PN"W69"23;
"MEA_DQS_H2"
$PN"W71"24;
"MEA_DQS_L6"
$PN"P69"25;
"MEB_CHECK4"
$PN"BT70"26;
"MEB_DATA13"
$PN"CN69"27;
"MEB_DATA24"
$PN"CY70"28;
"MEB_DQS_L0"
$PN"CE71"29;
"MEA_DATA18"
$PN"V70"30;
"MEA_DATA29"
$PN"AH69"31;
"MEA_DQS_H1"
$PN"N71"32;
"MEA_DQS_L5"
$PN"H69"33;
"MEB_CHECK3"
$PN"CB69"34;
"MEB_DATA12"
$PN"CM70"35;
"MEB_DATA23"
$PN"CY69"36;
"MEA_DATA17"
$PN"V69"37;
"MEA_DATA28"
$PN"AG71"38;
"MEA_DQS_H0"
$PN"G71"39;
"MEA_DQS_L4"
$PN"AM70"40;
"MEB_CHECK2"
$PN"CA71"41;
"MEB_DATA9"
$PN"CJ69"42;
"MEB_DATA11"
$PN"CK69"43;
"MEB_DATA22"
$PN"CW71"44;
"MEA0_RSP_L"
$PN"BN69"45;
"MEA1_RSP_L"
$PN"BP69"0;
"MEA_CHECK7"
$PN"AR69"46;
"MEA_DATA9"
$PN"M69"47;
"MEA_DATA16"
$PN"U71"48;
"MEA_DATA27"
$PN"AE69"49;
"MEA_DQS_L3"
$PN"AF70"50;
"MEB_CA6"
$PN"BK70"51;
"MEB_CHECK1"
$PN"CA69"52;
"MEB_DATA8"
$PN"CH70"53;
"MEB_DATA10"
$PN"CJ71"54;
"MEB_DATA21"
$PN"CW69"55;
"MEA_CA6"
$PN"BB69"56;
"MEA_CHECK6"
$PN"AP70"57;
"MEA_DATA8"
$PN"L71"58;
"MEA_DATA15"
$PN"U69"59;
"MEA_DATA26"
$PN"AD70"60;
"MEA_DQS_L2"
$PN"Y70"61;
"MEB_CA5"
$PN"BK69"62;
"MEB_CHECK0"
$PN"BY70"63;
"MEB_DATA7"
$PN"CH69"64;
"MEB_DATA20"
$PN"CV70"65;
"MEB_DATA31"
$PN"DF69"66;
"MEA_CA5"
$PN"BB70"67;
"MEA_CHECK5"
$PN"AP69"68;
"MEA_DATA7"
$PN"L69"69;
"MEA_DATA14"
$PN"T70"70;
"MEA_DATA25"
$PN"AD69"71;
"MEA_DQS_L1"
$PN"P70"72;
"MEB0_CS_L1"
$PN"BN71"73;
"MEB1_CS_L1"
$PN"BM70"0;
"MEB_CA4"
$PN"BJ69"74;
"MEB_DATA6"
$PN"CG71"75;
"MEB_DATA30"
$PN"DE71"76;
"MEB_DQS_H8"
$PN"DD69"77;
"MEA_CA4"
$PN"BA71"78;
"MEA_CHECK4"
$PN"AN71"79;
"MEA_DATA6"
$PN"K70"80;
"MEA_DATA13"
$PN"T69"81;
"MEA_DATA24"
$PN"AC71"82;
"MEA_DQS_L0"
$PN"H70"83;
"MEB0_CS_L0"
$PN"BM69"84;
"MEB1_CS_L0"
$PN"BL69"0;
"MEB_CA3"
$PN"BJ71"85;
"MEB_DATA5"
$PN"CG69"86;
"MEB_DQS_H7"
$PN"CV69"87;
"MEA_CA3"
$PN"BA69"88;
"MEA_CHECK3"
$PN"AL69"89;
"MEA_DATA5"
$PN"K69"90;
"MEA_DATA12"
$PN"R71"91;
"MEA_DATA23"
$PN"AC69"92;
"MEB_CA2"
$PN"BH70"93;
"MEB_DATA4"
$PN"CF70"94;
"MEB_DQS_H6"
$PN"CM69"95;
"MEA_CA2"
$PN"AY69"96;
"MEA_CHECK2"
$PN"AK70"97;
"MEA_DATA4"
$PN"J71"98;
"MEA_DATA11"
$PN"N69"99;
"MEA_DATA22"
$PN"AB70"100;
"MEB_CA1"
$PN"BH69"101;
"MEB_DATA3"
$PN"CD69"102;
"MEB_DQS_H5"
$PN"CF69"103;
"MEB_DQS_L9"
$PN"BW71"104;
"MEA_CA1"
$PN"AY70"105;
"MEA_CHECK1"
$PN"AK69"106;
"MEA_DATA3"
$PN"G69"107;
"MEA_DATA10"
$PN"M70"108;
"MEA_DATA21"
$PN"AB69"109;
"MEB_CA0"
$PN"BG69"110;
"MEB_DATA2"
$PN"CC71"111;
"MEB_DQS_H4"
$PN"BY69"112;
"MEB_DQS_L8"
$PN"DC69"113;
"MEA_CA0"
$PN"AW71"114;
"MEA_CHECK0"
$PN"AJ71"115;
"MEA_DATA2"
$PN"F70"116;
"MEA_DATA20"
$PN"AA71"117;
"MEA_DATA31"
$PN"AJ69"118;
"MEA_DQS_H9"
$PN"AN69"119;
"MEB_DATA1"
$PN"CC69"120;
"MEB_DQS_H3"
$PN"DB70"121;
"MEB_DQS_L7"
$PN"CU69"122;
"MEA0_CS_L1"
$PN"AW69"123;
"MEA1_CS_L1"
$PN"AV69"0;
"MEA_DATA1"
$PN"F69"124;
"MEA_DATA30"
$PN"AH70"125;
"MEA_DQS_H8"
$PN"AG69"126;
"MEB_DATA0"
$PN"CB70"127;
"MEB_DATA19"
$PN"CT69"128;
"MEB_DQS_H2"
$PN"CT70"129;
"MEB_DQS_L6"
$PN"CL69"130;
"MEA0_CS_L0"
$PN"AV70"131;
"MEA1_CS_L0"
$PN"AU71"0;
"MEA_DATA0"
$PN"E71"132;
"MEA_DQS_H7"
$PN"AA69"133;
"MEB_DATA18"
$PN"CR71"134;
"MEB_DATA29"
$PN"DE69"135;
"MEB_DQS_H1"
$PN"CK70"136;
"MEB_DQS_L5"
$PN"CE69"137;
"MEA_DQS_H6"
$PN"R69"138;
"MEB_DATA17"
$PN"CR69"139;
"MEB_DATA28"
$PN"DD70"140;
"MEB_DQS_H0"
$PN"CD70"141;
"MEB_DQS_L4"
$PN"BW69"142;
"MEA_DQS_H5"
$PN"J69"143;
"MEA_DQS_L9"
$PN"AM69"144;
"MEB0_RSP_L"
$PN"BP70"145;
"MEB1_RSP_L"
$PN"BR71"0;
"MEB_CHECK7"
$PN"BV69"146;
"MEB_DATA16"
$PN"CP70"147;
"MEB_DATA27"
$PN"DB69"148;
"MEB_DQS_L3"
$PN"DC71"149;
"MEA_DQS_H4"
$PN"AL71"150;
"MEA_DQS_L8"
$PN"AF69"151;
"MEB_CHECK6"
$PN"BU71"152;
"MEB_DATA15"
$PN"CP69"153;
"MEB_DATA26"
$PN"DA71"154;
"MEB_DQS_L2"
$PN"CU71"155;
"ME_RESET_L"
$PN"AU69"156;
"ME_ALERT_L"
$PN"AT69"157;
%"TAP"
"1","(-3400,6050)","0","mstr_standard","I162";
;
CDS_LIB"mstr_standard"
BODY_TYPE"PLUMBING"
HDL_TAP"TRUE";
"B \NAC \NWC"7;
"S \NAC"
BN"0"132;
%"TAP"
"1","(-3400,5900)","0","mstr_standard","I163";
;
CDS_LIB"mstr_standard"
BODY_TYPE"PLUMBING"
HDL_TAP"TRUE";
"B \NAC \NWC"7;
"S \NAC"
BN"3"107;
%"TAP"
"1","(-3400,6000)","0","mstr_standard","I164";
;
CDS_LIB"mstr_standard"
BODY_TYPE"PLUMBING"
HDL_TAP"TRUE";
"B \NAC \NWC"7;
"S \NAC"
BN"1"124;
%"TAP"
"1","(-3400,5950)","0","mstr_standard","I165";
;
CDS_LIB"mstr_standard"
BODY_TYPE"PLUMBING"
HDL_TAP"TRUE";
"B \NAC \NWC"7;
"S \NAC"
BN"2"116;
%"TAP"
"1","(-3400,5800)","0","mstr_standard","I166";
;
CDS_LIB"mstr_standard"
BODY_TYPE"PLUMBING"
HDL_TAP"TRUE";
"B \NAC \NWC"7;
"S \NAC"
BN"5"90;
%"TAP"
"1","(-3400,5850)","0","mstr_standard","I167";
;
CDS_LIB"mstr_standard"
BODY_TYPE"PLUMBING"
HDL_TAP"TRUE";
"B \NAC \NWC"7;
"S \NAC"
BN"4"98;
%"TAP"
"1","(-3400,5750)","0","mstr_standard","I168";
;
CDS_LIB"mstr_standard"
BODY_TYPE"PLUMBING"
HDL_TAP"TRUE";
"B \NAC \NWC"7;
"S \NAC"
BN"6"80;
%"TAP"
"1","(-3400,5700)","0","mstr_standard","I169";
;
CDS_LIB"mstr_standard"
BODY_TYPE"PLUMBING"
HDL_TAP"TRUE";
"B \NAC \NWC"7;
"S \NAC"
BN"7"69;
%"TAP"
"1","(-3400,5550)","0","mstr_standard","I170";
;
CDS_LIB"mstr_standard"
BODY_TYPE"PLUMBING"
HDL_TAP"TRUE";
"B \NAC \NWC"7;
"S \NAC"
BN"9"47;
%"TAP"
"1","(-3400,5600)","0","mstr_standard","I171";
;
CDS_LIB"mstr_standard"
BODY_TYPE"PLUMBING"
HDL_TAP"TRUE";
"B \NAC \NWC"7;
"S \NAC"
BN"8"58;
%"TAP"
"1","(-3400,5400)","0","mstr_standard","I172";
;
CDS_LIB"mstr_standard"
BODY_TYPE"PLUMBING"
HDL_TAP"TRUE";
"B \NAC \NWC"7;
"S \NAC"
BN"12"91;
%"TAP"
"1","(-3400,5450)","0","mstr_standard","I173";
;
CDS_LIB"mstr_standard"
BODY_TYPE"PLUMBING"
HDL_TAP"TRUE";
"B \NAC \NWC"7;
"S \NAC"
BN"11"99;
%"TAP"
"1","(-3400,5500)","0","mstr_standard","I174";
;
CDS_LIB"mstr_standard"
BODY_TYPE"PLUMBING"
HDL_TAP"TRUE";
"B \NAC \NWC"7;
"S \NAC"
BN"10"108;
%"TAP"
"1","(-3400,5250)","0","mstr_standard","I175";
;
CDS_LIB"mstr_standard"
BODY_TYPE"PLUMBING"
HDL_TAP"TRUE";
"B \NAC \NWC"7;
"S \NAC"
BN"15"59;
%"TAP"
"1","(-3400,5300)","0","mstr_standard","I176";
;
CDS_LIB"mstr_standard"
BODY_TYPE"PLUMBING"
HDL_TAP"TRUE";
"B \NAC \NWC"7;
"S \NAC"
BN"14"70;
%"TAP"
"1","(-3400,5350)","0","mstr_standard","I177";
;
CDS_LIB"mstr_standard"
BODY_TYPE"PLUMBING"
HDL_TAP"TRUE";
"B \NAC \NWC"7;
"S \NAC"
BN"13"81;
%"TAP"
"1","(-3400,5150)","0","mstr_standard","I178";
;
CDS_LIB"mstr_standard"
BODY_TYPE"PLUMBING"
HDL_TAP"TRUE";
"B \NAC \NWC"7;
"S \NAC"
BN"16"48;
%"TAP"
"1","(-3400,5050)","0","mstr_standard","I179";
;
CDS_LIB"mstr_standard"
BODY_TYPE"PLUMBING"
HDL_TAP"TRUE";
"B \NAC \NWC"7;
"S \NAC"
BN"18"30;
%"TAP"
"1","(-3400,5100)","0","mstr_standard","I180";
;
CDS_LIB"mstr_standard"
BODY_TYPE"PLUMBING"
HDL_TAP"TRUE";
"B \NAC \NWC"7;
"S \NAC"
BN"17"37;
%"TAP"
"1","(-3400,5000)","0","mstr_standard","I181";
;
CDS_LIB"mstr_standard"
BODY_TYPE"PLUMBING"
HDL_TAP"TRUE";
"B \NAC \NWC"7;
"S \NAC"
BN"19"23;
%"TAP"
"1","(-3400,4950)","0","mstr_standard","I182";
;
CDS_LIB"mstr_standard"
BODY_TYPE"PLUMBING"
HDL_TAP"TRUE";
"B \NAC \NWC"7;
"S \NAC"
BN"20"117;
%"TAP"
"1","(-3400,4900)","0","mstr_standard","I183";
;
CDS_LIB"mstr_standard"
BODY_TYPE"PLUMBING"
HDL_TAP"TRUE";
"B \NAC \NWC"7;
"S \NAC"
BN"21"109;
%"TAP"
"1","(-3400,4800)","0","mstr_standard","I184";
;
CDS_LIB"mstr_standard"
BODY_TYPE"PLUMBING"
HDL_TAP"TRUE";
"B \NAC \NWC"7;
"S \NAC"
BN"23"92;
%"TAP"
"1","(-3400,4850)","0","mstr_standard","I185";
;
CDS_LIB"mstr_standard"
BODY_TYPE"PLUMBING"
HDL_TAP"TRUE";
"B \NAC \NWC"7;
"S \NAC"
BN"22"100;
%"TAP"
"1","(-3400,4650)","0","mstr_standard","I186";
;
CDS_LIB"mstr_standard"
BODY_TYPE"PLUMBING"
HDL_TAP"TRUE";
"B \NAC \NWC"7;
"S \NAC"
BN"25"71;
%"TAP"
"1","(-3400,4700)","0","mstr_standard","I187";
;
CDS_LIB"mstr_standard"
BODY_TYPE"PLUMBING"
HDL_TAP"TRUE";
"B \NAC \NWC"7;
"S \NAC"
BN"24"82;
%"TAP"
"1","(-3400,4600)","0","mstr_standard","I188";
;
CDS_LIB"mstr_standard"
BODY_TYPE"PLUMBING"
HDL_TAP"TRUE";
"B \NAC \NWC"7;
"S \NAC"
BN"26"60;
%"TAP"
"1","(-3400,4550)","0","mstr_standard","I189";
;
CDS_LIB"mstr_standard"
BODY_TYPE"PLUMBING"
HDL_TAP"TRUE";
"B \NAC \NWC"7;
"S \NAC"
BN"27"49;
%"TAP"
"1","(-3400,4500)","0","mstr_standard","I190";
;
CDS_LIB"mstr_standard"
BODY_TYPE"PLUMBING"
HDL_TAP"TRUE";
"B \NAC \NWC"7;
"S \NAC"
BN"28"38;
%"TAP"
"1","(-3400,4450)","0","mstr_standard","I191";
;
CDS_LIB"mstr_standard"
BODY_TYPE"PLUMBING"
HDL_TAP"TRUE";
"B \NAC \NWC"7;
"S \NAC"
BN"29"31;
%"TAP"
"1","(-3400,4400)","0","mstr_standard","I192";
;
CDS_LIB"mstr_standard"
BODY_TYPE"PLUMBING"
HDL_TAP"TRUE";
"B \NAC \NWC"7;
"S \NAC"
BN"30"125;
%"TAP"
"1","(-3400,4350)","0","mstr_standard","I193";
;
CDS_LIB"mstr_standard"
BODY_TYPE"PLUMBING"
HDL_TAP"TRUE";
"B \NAC \NWC"7;
"S \NAC"
BN"31"118;
%"TAP"
"1","(-3400,4250)","0","mstr_standard","I194";
;
CDS_LIB"mstr_standard"
BODY_TYPE"PLUMBING"
HDL_TAP"TRUE";
"B \NAC \NWC"2;
"S \NAC"
BN"0"127;
%"TAP"
"1","(-3400,4100)","0","mstr_standard","I195";
;
CDS_LIB"mstr_standard"
BODY_TYPE"PLUMBING"
HDL_TAP"TRUE";
"B \NAC \NWC"2;
"S \NAC"
BN"3"102;
%"TAP"
"1","(-3400,4200)","0","mstr_standard","I196";
;
CDS_LIB"mstr_standard"
BODY_TYPE"PLUMBING"
HDL_TAP"TRUE";
"B \NAC \NWC"2;
"S \NAC"
BN"1"120;
%"TAP"
"1","(-3400,4150)","0","mstr_standard","I197";
;
CDS_LIB"mstr_standard"
BODY_TYPE"PLUMBING"
HDL_TAP"TRUE";
"B \NAC \NWC"2;
"S \NAC"
BN"2"111;
%"TAP"
"1","(-3400,4000)","0","mstr_standard","I199";
;
CDS_LIB"mstr_standard"
BODY_TYPE"PLUMBING"
HDL_TAP"TRUE";
"B \NAC \NWC"2;
"S \NAC"
BN"5"86;
%"TAP"
"1","(-3400,4050)","0","mstr_standard","I200";
;
CDS_LIB"mstr_standard"
BODY_TYPE"PLUMBING"
HDL_TAP"TRUE";
"B \NAC \NWC"2;
"S \NAC"
BN"4"94;
%"TAP"
"1","(-3400,3950)","0","mstr_standard","I201";
;
CDS_LIB"mstr_standard"
BODY_TYPE"PLUMBING"
HDL_TAP"TRUE";
"B \NAC \NWC"2;
"S \NAC"
BN"6"75;
%"TAP"
"1","(-3400,3900)","0","mstr_standard","I202";
;
CDS_LIB"mstr_standard"
BODY_TYPE"PLUMBING"
HDL_TAP"TRUE";
"B \NAC \NWC"2;
"S \NAC"
BN"7"64;
%"TAP"
"1","(-3400,3800)","0","mstr_standard","I203";
;
CDS_LIB"mstr_standard"
BODY_TYPE"PLUMBING"
HDL_TAP"TRUE";
"B \NAC \NWC"2;
"S \NAC"
BN"8"53;
%"TAP"
"1","(-3400,3750)","0","mstr_standard","I204";
;
CDS_LIB"mstr_standard"
BODY_TYPE"PLUMBING"
HDL_TAP"TRUE";
"B \NAC \NWC"2;
"S \NAC"
BN"9"42;
%"TAP"
"1","(-3400,3600)","0","mstr_standard","I205";
;
CDS_LIB"mstr_standard"
BODY_TYPE"PLUMBING"
HDL_TAP"TRUE";
"B \NAC \NWC"2;
"S \NAC"
BN"12"35;
%"TAP"
"1","(-3400,3650)","0","mstr_standard","I206";
;
CDS_LIB"mstr_standard"
BODY_TYPE"PLUMBING"
HDL_TAP"TRUE";
"B \NAC \NWC"2;
"S \NAC"
BN"11"43;
%"TAP"
"1","(-3400,3700)","0","mstr_standard","I207";
;
CDS_LIB"mstr_standard"
BODY_TYPE"PLUMBING"
HDL_TAP"TRUE";
"B \NAC \NWC"2;
"S \NAC"
BN"10"54;
%"TAP"
"1","(-3400,3500)","0","mstr_standard","I208";
;
CDS_LIB"mstr_standard"
BODY_TYPE"PLUMBING"
HDL_TAP"TRUE";
"B \NAC \NWC"2;
"S \NAC"
BN"14"20;
%"TAP"
"1","(-3400,3550)","0","mstr_standard","I209";
;
CDS_LIB"mstr_standard"
BODY_TYPE"PLUMBING"
HDL_TAP"TRUE";
"B \NAC \NWC"2;
"S \NAC"
BN"13"27;
%"TAP"
"1","(-3400,3450)","0","mstr_standard","I210";
;
CDS_LIB"mstr_standard"
BODY_TYPE"PLUMBING"
HDL_TAP"TRUE";
"B \NAC \NWC"2;
"S \NAC"
BN"15"153;
%"TAP"
"1","(-3400,3350)","0","mstr_standard","I211";
;
CDS_LIB"mstr_standard"
BODY_TYPE"PLUMBING"
HDL_TAP"TRUE";
"B \NAC \NWC"2;
"S \NAC"
BN"16"147;
%"TAP"
"1","(-3400,3300)","0","mstr_standard","I212";
;
CDS_LIB"mstr_standard"
BODY_TYPE"PLUMBING"
HDL_TAP"TRUE";
"B \NAC \NWC"2;
"S \NAC"
BN"17"139;
%"TAP"
"1","(-3400,3250)","0","mstr_standard","I213";
;
CDS_LIB"mstr_standard"
BODY_TYPE"PLUMBING"
HDL_TAP"TRUE";
"B \NAC \NWC"2;
"S \NAC"
BN"18"134;
%"TAP"
"1","(-3400,3200)","0","mstr_standard","I214";
;
CDS_LIB"mstr_standard"
BODY_TYPE"PLUMBING"
HDL_TAP"TRUE";
"B \NAC \NWC"2;
"S \NAC"
BN"19"128;
%"TAP"
"1","(-3400,3150)","0","mstr_standard","I215";
;
CDS_LIB"mstr_standard"
BODY_TYPE"PLUMBING"
HDL_TAP"TRUE";
"B \NAC \NWC"2;
"S \NAC"
BN"20"65;
%"TAP"
"1","(-3400,3100)","0","mstr_standard","I216";
;
CDS_LIB"mstr_standard"
BODY_TYPE"PLUMBING"
HDL_TAP"TRUE";
"B \NAC \NWC"2;
"S \NAC"
BN"21"55;
%"TAP"
"1","(-3400,3000)","0","mstr_standard","I217";
;
CDS_LIB"mstr_standard"
BODY_TYPE"PLUMBING"
HDL_TAP"TRUE";
"B \NAC \NWC"2;
"S \NAC"
BN"23"36;
%"TAP"
"1","(-3400,3050)","0","mstr_standard","I218";
;
CDS_LIB"mstr_standard"
BODY_TYPE"PLUMBING"
HDL_TAP"TRUE";
"B \NAC \NWC"2;
"S \NAC"
BN"22"44;
%"TAP"
"1","(-3400,2900)","0","mstr_standard","I219";
;
CDS_LIB"mstr_standard"
BODY_TYPE"PLUMBING"
HDL_TAP"TRUE";
"B \NAC \NWC"2;
"S \NAC"
BN"24"28;
%"TAP"
"1","(-3400,2850)","0","mstr_standard","I220";
;
CDS_LIB"mstr_standard"
BODY_TYPE"PLUMBING"
HDL_TAP"TRUE";
"B \NAC \NWC"2;
"S \NAC"
BN"25"21;
%"TAP"
"1","(-3400,2800)","0","mstr_standard","I221";
;
CDS_LIB"mstr_standard"
BODY_TYPE"PLUMBING"
HDL_TAP"TRUE";
"B \NAC \NWC"2;
"S \NAC"
BN"26"154;
%"TAP"
"1","(-3400,2750)","0","mstr_standard","I222";
;
CDS_LIB"mstr_standard"
BODY_TYPE"PLUMBING"
HDL_TAP"TRUE";
"B \NAC \NWC"2;
"S \NAC"
BN"27"148;
%"TAP"
"1","(-3400,2700)","0","mstr_standard","I223";
;
CDS_LIB"mstr_standard"
BODY_TYPE"PLUMBING"
HDL_TAP"TRUE";
"B \NAC \NWC"2;
"S \NAC"
BN"28"140;
%"TAP"
"1","(-3400,2650)","0","mstr_standard","I224";
;
CDS_LIB"mstr_standard"
BODY_TYPE"PLUMBING"
HDL_TAP"TRUE";
"B \NAC \NWC"2;
"S \NAC"
BN"29"135;
%"TAP"
"1","(-3400,2600)","0","mstr_standard","I225";
;
CDS_LIB"mstr_standard"
BODY_TYPE"PLUMBING"
HDL_TAP"TRUE";
"B \NAC \NWC"2;
"S \NAC"
BN"30"76;
%"TAP"
"1","(-3400,2450)","0","mstr_standard","I226";
;
CDS_LIB"mstr_standard"
BODY_TYPE"PLUMBING"
HDL_TAP"TRUE";
"B \NAC \NWC"8;
"S \NAC"
BN"0"115;
%"TAP"
"1","(-3400,2550)","0","mstr_standard","I227";
;
CDS_LIB"mstr_standard"
BODY_TYPE"PLUMBING"
HDL_TAP"TRUE";
"B \NAC \NWC"2;
"S \NAC"
BN"31"66;
%"TAP"
"1","(-3400,2350)","0","mstr_standard","I228";
;
CDS_LIB"mstr_standard"
BODY_TYPE"PLUMBING"
HDL_TAP"TRUE";
"B \NAC \NWC"8;
"S \NAC"
BN"2"97;
%"TAP"
"1","(-3400,2400)","0","mstr_standard","I229";
;
CDS_LIB"mstr_standard"
BODY_TYPE"PLUMBING"
HDL_TAP"TRUE";
"B \NAC \NWC"8;
"S \NAC"
BN"1"106;
%"TAP"
"1","(-3400,2250)","0","mstr_standard","I230";
;
CDS_LIB"mstr_standard"
BODY_TYPE"PLUMBING"
HDL_TAP"TRUE";
"B \NAC \NWC"8;
"S \NAC"
BN"4"79;
%"TAP"
"1","(-3400,2300)","0","mstr_standard","I231";
;
CDS_LIB"mstr_standard"
BODY_TYPE"PLUMBING"
HDL_TAP"TRUE";
"B \NAC \NWC"8;
"S \NAC"
BN"3"89;
%"TAP"
"1","(-3400,2200)","0","mstr_standard","I232";
;
CDS_LIB"mstr_standard"
BODY_TYPE"PLUMBING"
HDL_TAP"TRUE";
"B \NAC \NWC"8;
"S \NAC"
BN"5"68;
%"TAP"
"1","(-3400,2150)","0","mstr_standard","I233";
;
CDS_LIB"mstr_standard"
BODY_TYPE"PLUMBING"
HDL_TAP"TRUE";
"B \NAC \NWC"8;
"S \NAC"
BN"6"57;
%"TAP"
"1","(-3400,2100)","0","mstr_standard","I234";
;
CDS_LIB"mstr_standard"
BODY_TYPE"PLUMBING"
HDL_TAP"TRUE";
"B \NAC \NWC"8;
"S \NAC"
BN"7"46;
%"TAP"
"1","(-3400,1950)","0","mstr_standard","I236";
;
CDS_LIB"mstr_standard"
BODY_TYPE"PLUMBING"
HDL_TAP"TRUE";
"B \NAC \NWC"3;
"S \NAC"
BN"1"52;
%"TAP"
"1","(-3400,2000)","0","mstr_standard","I237";
;
CDS_LIB"mstr_standard"
BODY_TYPE"PLUMBING"
HDL_TAP"TRUE";
"B \NAC \NWC"3;
"S \NAC"
BN"0"63;
%"TAP"
"1","(-3400,1800)","0","mstr_standard","I238";
;
CDS_LIB"mstr_standard"
BODY_TYPE"PLUMBING"
HDL_TAP"TRUE";
"B \NAC \NWC"3;
"S \NAC"
BN"4"26;
%"TAP"
"1","(-3400,1900)","0","mstr_standard","I239";
;
CDS_LIB"mstr_standard"
BODY_TYPE"PLUMBING"
HDL_TAP"TRUE";
"B \NAC \NWC"3;
"S \NAC"
BN"2"41;
%"TAP"
"1","(-3400,1850)","0","mstr_standard","I240";
;
CDS_LIB"mstr_standard"
BODY_TYPE"PLUMBING"
HDL_TAP"TRUE";
"B \NAC \NWC"3;
"S \NAC"
BN"3"34;
%"TAP"
"1","(-3400,1700)","0","mstr_standard","I241";
;
CDS_LIB"mstr_standard"
BODY_TYPE"PLUMBING"
HDL_TAP"TRUE";
"B \NAC \NWC"3;
"S \NAC"
BN"6"152;
%"TAP"
"1","(-3400,1750)","0","mstr_standard","I242";
;
CDS_LIB"mstr_standard"
BODY_TYPE"PLUMBING"
HDL_TAP"TRUE";
"B \NAC \NWC"3;
"S \NAC"
BN"5"19;
%"TAP"
"1","(-3400,1650)","0","mstr_standard","I243";
;
CDS_LIB"mstr_standard"
BODY_TYPE"PLUMBING"
HDL_TAP"TRUE";
"B \NAC \NWC"3;
"S \NAC"
BN"7"146;
%"TAP"
"1","(-5825,6050)","2","mstr_standard","I244";
;
CDS_LIB"mstr_standard"
BODY_TYPE"PLUMBING"
HDL_TAP"TRUE";
"B \NAC \NWC"5;
"S \NAC"
BN"0"39;
%"TAP"
"1","(-5825,5950)","2","mstr_standard","I245";
;
CDS_LIB"mstr_standard"
BODY_TYPE"PLUMBING"
HDL_TAP"TRUE";
"B \NAC \NWC"5;
"S \NAC"
BN"1"32;
%"TAP"
"1","(-5825,5750)","2","mstr_standard","I246";
;
CDS_LIB"mstr_standard"
BODY_TYPE"PLUMBING"
HDL_TAP"TRUE";
"B \NAC \NWC"5;
"S \NAC"
BN"3"17;
%"TAP"
"1","(-5825,5850)","2","mstr_standard","I247";
;
CDS_LIB"mstr_standard"
BODY_TYPE"PLUMBING"
HDL_TAP"TRUE";
"B \NAC \NWC"5;
"S \NAC"
BN"2"24;
%"TAP"
"1","(-5825,5650)","2","mstr_standard","I248";
;
CDS_LIB"mstr_standard"
BODY_TYPE"PLUMBING"
HDL_TAP"TRUE";
"B \NAC \NWC"5;
"S \NAC"
BN"4"150;
%"TAP"
"1","(-6025,6000)","2","mstr_standard","I249";
;
CDS_LIB"mstr_standard"
BODY_TYPE"PLUMBING"
HDL_TAP"TRUE";
"B \NAC \NWC"4;
"S \NAC"
BN"0"83;
%"TAP"
"1","(-6025,5900)","2","mstr_standard","I250";
;
CDS_LIB"mstr_standard"
BODY_TYPE"PLUMBING"
HDL_TAP"TRUE";
"B \NAC \NWC"4;
"S \NAC"
BN"1"72;
%"TAP"
"1","(-6025,5800)","2","mstr_standard","I251";
;
CDS_LIB"mstr_standard"
BODY_TYPE"PLUMBING"
HDL_TAP"TRUE";
"B \NAC \NWC"4;
"S \NAC"
BN"2"61;
%"TAP"
"1","(-6025,5700)","2","mstr_standard","I252";
;
CDS_LIB"mstr_standard"
BODY_TYPE"PLUMBING"
HDL_TAP"TRUE";
"B \NAC \NWC"4;
"S \NAC"
BN"3"50;
%"TAP"
"1","(-5825,5550)","2","mstr_standard","I253";
;
CDS_LIB"mstr_standard"
BODY_TYPE"PLUMBING"
HDL_TAP"TRUE";
"B \NAC \NWC"5;
"S \NAC"
BN"5"143;
%"TAP"
"1","(-5825,5450)","2","mstr_standard","I254";
;
CDS_LIB"mstr_standard"
BODY_TYPE"PLUMBING"
HDL_TAP"TRUE";
"B \NAC \NWC"5;
"S \NAC"
BN"6"138;
%"TAP"
"1","(-5825,5250)","2","mstr_standard","I255";
;
CDS_LIB"mstr_standard"
BODY_TYPE"PLUMBING"
HDL_TAP"TRUE";
"B \NAC \NWC"5;
"S \NAC"
BN"8"126;
%"TAP"
"1","(-5825,5350)","2","mstr_standard","I256";
;
CDS_LIB"mstr_standard"
BODY_TYPE"PLUMBING"
HDL_TAP"TRUE";
"B \NAC \NWC"5;
"S \NAC"
BN"7"133;
%"TAP"
"1","(-5825,5150)","2","mstr_standard","I257";
;
CDS_LIB"mstr_standard"
BODY_TYPE"PLUMBING"
HDL_TAP"TRUE";
"B \NAC \NWC"5;
"S \NAC"
BN"9"119;
%"TAP"
"1","(-6025,5600)","2","mstr_standard","I258";
;
CDS_LIB"mstr_standard"
BODY_TYPE"PLUMBING"
HDL_TAP"TRUE";
"B \NAC \NWC"4;
"S \NAC"
BN"4"40;
%"TAP"
"1","(-6025,5500)","2","mstr_standard","I259";
;
CDS_LIB"mstr_standard"
BODY_TYPE"PLUMBING"
HDL_TAP"TRUE";
"B \NAC \NWC"4;
"S \NAC"
BN"5"33;
%"TAP"
"1","(-6025,5400)","2","mstr_standard","I260";
;
CDS_LIB"mstr_standard"
BODY_TYPE"PLUMBING"
HDL_TAP"TRUE";
"B \NAC \NWC"4;
"S \NAC"
BN"6"25;
%"TAP"
"1","(-6025,5300)","2","mstr_standard","I261";
;
CDS_LIB"mstr_standard"
BODY_TYPE"PLUMBING"
HDL_TAP"TRUE";
"B \NAC \NWC"4;
"S \NAC"
BN"7"18;
%"TAP"
"1","(-6025,5200)","2","mstr_standard","I262";
;
CDS_LIB"mstr_standard"
BODY_TYPE"PLUMBING"
HDL_TAP"TRUE";
"B \NAC \NWC"4;
"S \NAC"
BN"8"151;
%"TAP"
"1","(-5825,4900)","2","mstr_standard","I263";
;
CDS_LIB"mstr_standard"
BODY_TYPE"PLUMBING"
HDL_TAP"TRUE";
"B \NAC \NWC"6;
"S \NAC"
BN"1"136;
%"TAP"
"1","(-5825,5000)","2","mstr_standard","I264";
;
CDS_LIB"mstr_standard"
BODY_TYPE"PLUMBING"
HDL_TAP"TRUE";
"B \NAC \NWC"6;
"S \NAC"
BN"0"141;
%"TAP"
"1","(-5825,4800)","2","mstr_standard","I265";
;
CDS_LIB"mstr_standard"
BODY_TYPE"PLUMBING"
HDL_TAP"TRUE";
"B \NAC \NWC"6;
"S \NAC"
BN"2"129;
%"TAP"
"1","(-5825,4700)","2","mstr_standard","I266";
;
CDS_LIB"mstr_standard"
BODY_TYPE"PLUMBING"
HDL_TAP"TRUE";
"B \NAC \NWC"6;
"S \NAC"
BN"3"121;
%"TAP"
"1","(-6025,4950)","2","mstr_standard","I267";
;
CDS_LIB"mstr_standard"
BODY_TYPE"PLUMBING"
HDL_TAP"TRUE";
"B \NAC \NWC"1;
"S \NAC"
BN"0"29;
%"TAP"
"1","(-6025,5100)","2","mstr_standard","I268";
;
CDS_LIB"mstr_standard"
BODY_TYPE"PLUMBING"
HDL_TAP"TRUE";
"B \NAC \NWC"4;
"S \NAC"
BN"9"144;
%"TAP"
"1","(-6025,4850)","2","mstr_standard","I269";
;
CDS_LIB"mstr_standard"
BODY_TYPE"PLUMBING"
HDL_TAP"TRUE";
"B \NAC \NWC"1;
"S \NAC"
BN"1"22;
%"TAP"
"1","(-6025,4750)","2","mstr_standard","I270";
;
CDS_LIB"mstr_standard"
BODY_TYPE"PLUMBING"
HDL_TAP"TRUE";
"B \NAC \NWC"1;
"S \NAC"
BN"2"155;
%"TAP"
"1","(-6025,4650)","2","mstr_standard","I271";
;
CDS_LIB"mstr_standard"
BODY_TYPE"PLUMBING"
HDL_TAP"TRUE";
"B \NAC \NWC"1;
"S \NAC"
BN"3"149;
%"TAP"
"1","(-5825,4600)","2","mstr_standard","I272";
;
CDS_LIB"mstr_standard"
BODY_TYPE"PLUMBING"
HDL_TAP"TRUE";
"B \NAC \NWC"6;
"S \NAC"
BN"4"112;
%"TAP"
"1","(-5825,4500)","2","mstr_standard","I273";
;
CDS_LIB"mstr_standard"
BODY_TYPE"PLUMBING"
HDL_TAP"TRUE";
"B \NAC \NWC"6;
"S \NAC"
BN"5"103;
%"TAP"
"1","(-5825,4400)","2","mstr_standard","I274";
;
CDS_LIB"mstr_standard"
BODY_TYPE"PLUMBING"
HDL_TAP"TRUE";
"B \NAC \NWC"6;
"S \NAC"
BN"6"95;
%"TAP"
"1","(-5825,4200)","2","mstr_standard","I275";
;
CDS_LIB"mstr_standard"
BODY_TYPE"PLUMBING"
HDL_TAP"TRUE";
"B \NAC \NWC"6;
"S \NAC"
BN"8"77;
%"TAP"
"1","(-5825,4300)","2","mstr_standard","I276";
;
CDS_LIB"mstr_standard"
BODY_TYPE"PLUMBING"
HDL_TAP"TRUE";
"B \NAC \NWC"6;
"S \NAC"
BN"7"87;
%"TAP"
"1","(-5825,4100)","2","mstr_standard","I277";
;
CDS_LIB"mstr_standard"
BODY_TYPE"PLUMBING"
HDL_TAP"TRUE";
"B \NAC \NWC"6;
"S \NAC"
BN"9"14;
%"TAP"
"1","(-6025,4550)","2","mstr_standard","I278";
;
CDS_LIB"mstr_standard"
BODY_TYPE"PLUMBING"
HDL_TAP"TRUE";
"B \NAC \NWC"1;
"S \NAC"
BN"4"142;
%"TAP"
"1","(-6025,4450)","2","mstr_standard","I279";
;
CDS_LIB"mstr_standard"
BODY_TYPE"PLUMBING"
HDL_TAP"TRUE";
"B \NAC \NWC"1;
"S \NAC"
BN"5"137;
%"TAP"
"1","(-6025,4350)","2","mstr_standard","I280";
;
CDS_LIB"mstr_standard"
BODY_TYPE"PLUMBING"
HDL_TAP"TRUE";
"B \NAC \NWC"1;
"S \NAC"
BN"6"130;
%"TAP"
"1","(-6025,4250)","2","mstr_standard","I281";
;
CDS_LIB"mstr_standard"
BODY_TYPE"PLUMBING"
HDL_TAP"TRUE";
"B \NAC \NWC"1;
"S \NAC"
BN"7"122;
%"TAP"
"1","(-6025,4150)","2","mstr_standard","I282";
;
CDS_LIB"mstr_standard"
BODY_TYPE"PLUMBING"
HDL_TAP"TRUE";
"B \NAC \NWC"1;
"S \NAC"
BN"8"113;
%"TAP"
"1","(-6025,4050)","2","mstr_standard","I287";
;
CDS_LIB"mstr_standard"
BODY_TYPE"PLUMBING"
HDL_TAP"TRUE";
"B \NAC \NWC"1;
"S \NAC"
BN"9"104;
%"TAP"
"1","(-6025,3900)","2","mstr_standard","I288";
;
CDS_LIB"mstr_standard"
BODY_TYPE"PLUMBING"
HDL_TAP"TRUE";
"B \NAC \NWC"9;
"S \NAC"
BN"0"114;
%"TAP"
"1","(-6025,3850)","2","mstr_standard","I289";
;
CDS_LIB"mstr_standard"
BODY_TYPE"PLUMBING"
HDL_TAP"TRUE";
"B \NAC \NWC"9;
"S \NAC"
BN"1"105;
%"TAP"
"1","(-6025,3800)","2","mstr_standard","I290";
;
CDS_LIB"mstr_standard"
BODY_TYPE"PLUMBING"
HDL_TAP"TRUE";
"B \NAC \NWC"9;
"S \NAC"
BN"2"96;
%"TAP"
"1","(-6025,3750)","2","mstr_standard","I291";
;
CDS_LIB"mstr_standard"
BODY_TYPE"PLUMBING"
HDL_TAP"TRUE";
"B \NAC \NWC"9;
"S \NAC"
BN"3"88;
%"TAP"
"1","(-6025,3600)","2","mstr_standard","I292";
;
CDS_LIB"mstr_standard"
BODY_TYPE"PLUMBING"
HDL_TAP"TRUE";
"B \NAC \NWC"9;
"S \NAC"
BN"6"56;
%"TAP"
"1","(-6025,3650)","2","mstr_standard","I293";
;
CDS_LIB"mstr_standard"
BODY_TYPE"PLUMBING"
HDL_TAP"TRUE";
"B \NAC \NWC"9;
"S \NAC"
BN"5"67;
%"TAP"
"1","(-6025,3700)","2","mstr_standard","I294";
;
CDS_LIB"mstr_standard"
BODY_TYPE"PLUMBING"
HDL_TAP"TRUE";
"B \NAC \NWC"9;
"S \NAC"
BN"4"78;
%"TAP"
"1","(-6025,3500)","2","mstr_standard","I295";
;
CDS_LIB"mstr_standard"
BODY_TYPE"PLUMBING"
HDL_TAP"TRUE";
"B \NAC \NWC"10;
"S \NAC"
BN"0"110;
%"TAP"
"1","(-6025,3450)","2","mstr_standard","I296";
;
CDS_LIB"mstr_standard"
BODY_TYPE"PLUMBING"
HDL_TAP"TRUE";
"B \NAC \NWC"10;
"S \NAC"
BN"1"101;
%"TAP"
"1","(-6025,3350)","2","mstr_standard","I297";
;
CDS_LIB"mstr_standard"
BODY_TYPE"PLUMBING"
HDL_TAP"TRUE";
"B \NAC \NWC"10;
"S \NAC"
BN"3"85;
%"TAP"
"1","(-6025,3400)","2","mstr_standard","I298";
;
CDS_LIB"mstr_standard"
BODY_TYPE"PLUMBING"
HDL_TAP"TRUE";
"B \NAC \NWC"10;
"S \NAC"
BN"2"93;
%"TAP"
"1","(-6025,3300)","2","mstr_standard","I299";
;
CDS_LIB"mstr_standard"
BODY_TYPE"PLUMBING"
HDL_TAP"TRUE";
"B \NAC \NWC"10;
"S \NAC"
BN"4"74;
%"TAP"
"1","(-6025,3250)","2","mstr_standard","I300";
;
CDS_LIB"mstr_standard"
BODY_TYPE"PLUMBING"
HDL_TAP"TRUE";
"B \NAC \NWC"10;
"S \NAC"
BN"5"62;
%"TAP"
"1","(-6025,3200)","2","mstr_standard","I301";
;
CDS_LIB"mstr_standard"
BODY_TYPE"PLUMBING"
HDL_TAP"TRUE";
"B \NAC \NWC"10;
"S \NAC"
BN"6"51;
%"Q_RES"
"1","(-6950,2200)","0","pure_quanta","I315";
;
LOCATION"R379"
$SEC"1"
CDS_SEC"1"
PACK_TYPE"0402LF"
TOLERANCE"1%"
VALUE"15"
MATERIAL"CHIP"
WATTAGE"1/16W"
CDS_LIB"pure_quanta"
PART_NUMBER"CS01502FB03";
"B"
$PN"2"157;
"A"
$PN"1"158;
END.
